(kicad_pcb
	(version 20241229)
	(generator "pcbnew")
	(generator_version "9.0")
	(general
		(thickness 1.711)
		(legacy_teardrops no)
	)
	(paper "A4")
	(title_block
		(title "Antmicro Baseboard for Jetson AGX Thor")
		(date "2026-02-18")
		(rev "1.1.0")
		(company "Antmicro Ltd")
		(comment 1 "www.antmicro.com")
		(comment 9 "footprints 611-613 of 1170")
	)
	(layers
		(0 "F.Cu" signal)
		(4 "In1.Cu" signal)
		(6 "In2.Cu" signal)
		(8 "In3.Cu" signal)
		(10 "In4.Cu" jumper)
		(12 "In5.Cu" signal)
		(14 "In6.Cu" signal)
		(16 "In7.Cu" signal)
		(18 "In8.Cu" signal)
		(2 "B.Cu" signal)
		(9 "F.Adhes" user "F.Adhesive")
		(11 "B.Adhes" user "B.Adhesive")
		(13 "F.Paste" user)
		(15 "B.Paste" user)
		(5 "F.SilkS" user "F.Silkscreen")
		(7 "B.SilkS" user "B.Silkscreen")
		(1 "F.Mask" user)
		(3 "B.Mask" user)
		(17 "Dwgs.User" user "User.Drawings")
		(19 "Cmts.User" user "User.Comments")
		(21 "Eco1.User" user "User.Eco1")
		(23 "Eco2.User" user "User.Eco2")
		(25 "Edge.Cuts" user)
		(27 "Margin" user)
		(31 "F.CrtYd" user "F.Courtyard")
		(29 "B.CrtYd" user "B.Courtyard")
		(35 "F.Fab" user)
		(33 "B.Fab" user)
	)
	(footprint "antmicro-footprints:USB-C_Receptacle_Kycon_KUSBX-SL2-CS1N24-B-TR"
		(locked yes)
		(layer "F.Cu")
		(at 236.455532 89.21 90)
		(descr "USB-C (USB TYPE-C) USB 3.2 Gen 2 (USB 3.1 Gen 2, Superspeed + (USB 3.1)) Receptacle Connector 24 Position Through Hole, Right Angle")
		(tags "CONNECTOR, USB")
		(property "Reference" "J9"
			(at 3.21 -10.785532 180)
			(layer "F.SilkS")
			(effects
				(font
					(size 0.7 0.7)
					(thickness 0.15)
				)
				(justify left bottom)
			)
		)
		(property "Value" "USB-C_Kycon_KUSBX-SL2-CS1N24-B-TR"
			(at 0 7.5 90)
			(layer "F.Fab")
			(effects
				(font
					(size 0.7 0.7)
					(thickness 0.15)
				)
				(justify right top)
			)
		)
		(property "Datasheet" "https://www.kycon.com/Pub_Eng_Draw/KUSBX-SL2-CS1N24-B-TR.pdf"
			(at 0 0 90)
			(layer "F.Fab")
			(hide yes)
			(effects
				(font
					(size 1.27 1.27)
					(thickness 0.15)
				)
			)
		)
		(property "Description" "USB-C (USB TYPE-C) USB 3.2 Gen 2 (USB 3.1 Gen 2, Superspeed + (USB 3.1)) USB PD Receptacle Connector 24 Position Surface Mount"
			(at 0 0 90)
			(layer "F.Fab")
			(hide yes)
			(effects
				(font
					(size 1.27 1.27)
					(thickness 0.15)
				)
			)
		)
		(property "MPN" "KUSBX-SL2-CS1N24-B-TR"
			(at 0 0 90)
			(unlocked yes)
			(layer "F.Fab")
			(hide yes)
			(effects
				(font
					(size 1 1)
					(thickness 0.15)
				)
			)
		)
		(property "Manufacturer" "Kycon"
			(at 0 0 90)
			(unlocked yes)
			(layer "F.Fab")
			(hide yes)
			(effects
				(font
					(size 1 1)
					(thickness 0.15)
				)
			)
		)
		(property "License" "Apache-2.0"
			(at 0 0 90)
			(unlocked yes)
			(layer "F.Fab")
			(hide yes)
			(effects
				(font
					(size 1 1)
					(thickness 0.15)
				)
			)
		)
		(property "Author" "Antmicro"
			(at 0 0 90)
			(unlocked yes)
			(layer "F.Fab")
			(hide yes)
			(effects
				(font
					(size 1 1)
					(thickness 0.15)
				)
			)
		)
		(sheetname "/USB DP Alt mode/")
		(sheetfile "usb_dp.kicad_sch")
		(attr smd)
		(fp_line
			(start 1 -8.8)
			(end 1 -8.8)
			(stroke
				(width 0.15)
				(type solid)
			)
			(layer "F.SilkS")
		)
		(fp_line
			(start 1 -8.8)
			(end -1 -8.8)
			(stroke
				(width 0.15)
				(type solid)
			)
			(layer "F.SilkS")
		)
		(fp_line
			(start -1 -8.8)
			(end 1 -8.8)
			(stroke
				(width 0.15)
				(type solid)
			)
			(layer "F.SilkS")
		)
		(fp_line
			(start -1 -8.8)
			(end -1 -8.8)
			(stroke
				(width 0.15)
				(type solid)
			)
			(layer "F.SilkS")
		)
		(fp_rect
			(start -4 -9.4)
			(end 4 5.65)
			(stroke
				(width 0.05)
				(type solid)
			)
			(fill no)
			(layer "F.CrtYd")
		)
		(fp_line
			(start 2.25 -8.8)
			(end -2.25 -8.8)
			(stroke
				(width 0.15)
				(type solid)
			)
			(layer "F.Fab")
		)
		(fp_line
			(start -2.25 -8.8)
			(end -2.25 5.5)
			(stroke
				(width 0.15)
				(type solid)
			)
			(layer "F.Fab")
		)
		(fp_line
			(start 2.25 5.5)
			(end 2.25 -8.8)
			(stroke
				(width 0.15)
				(type solid)
			)
			(layer "F.Fab")
		)
		(fp_line
			(start -2.25 5.5)
			(end 2.25 5.5)
			(stroke
				(width 0.15)
				(type solid)
			)
			(layer "F.Fab")
		)
		(fp_text user "License: Apache-2.0"
			(at -5.47 10.9 90)
			(layer "F.Fab")
			(effects
				(font
					(size 0.7 0.7)
					(thickness 0.15)
				)
				(justify left bottom)
			)
		)
		(fp_text user "${REFERENCE}"
			(at -5.47 8.5 90)
			(layer "F.Fab")
			(effects
				(font
					(size 0.7 0.7)
					(thickness 0.15)
				)
				(justify left bottom)
			)
		)
		(fp_text user "Author: Antmicro"
			(at -5.47 9.7 90)
			(layer "F.Fab")
			(effects
				(font
					(size 0.7 0.7)
					(thickness 0.15)
				)
				(justify left bottom)
			)
		)
		(pad "" np_thru_hole circle
			(at 0 -7.6 90)
			(size 1.1 1.1)
			(drill 1.1)
			(layers "*.Cu" "*.Mask")
		)
		(pad "" np_thru_hole circle
			(at 0 0 90)
			(size 1 1)
			(drill 1)
			(layers "*.Cu" "*.Mask")
		)
		(pad "A1" smd rect
			(at 1.1375 -6.525 180)
			(size 0.25 1.625)
			(layers "F.Cu" "F.Mask" "F.Paste")
			(net 1 "GND")
			(pinfunction "GND")
			(pintype "power_in")
		)
		(pad "A2" smd rect
			(at 1.1375 -6.025 180)
			(size 0.25 1.625)
			(layers "F.Cu" "F.Mask" "F.Paste")
			(net 345 "/USB DP Alt mode/USBC1_CONN_TX1_P")
			(pinfunction "TX_{1}+")
			(pintype "bidirectional")
		)
		(pad "A3" smd rect
			(at 1.1375 -5.525 180)
			(size 0.25 1.625)
			(layers "F.Cu" "F.Mask" "F.Paste")
			(net 361 "/USB DP Alt mode/USBC1_CONN_TX1_N")
			(pinfunction "TX_{1}-")
			(pintype "bidirectional")
		)
		(pad "A4" smd rect
			(at 1.1375 -5.025 180)
			(size 0.25 1.625)
			(layers "F.Cu" "F.Mask" "F.Paste")
			(net 376 "/USB DP Alt mode/USBC1_VBUS")
			(pinfunction "VBUS")
			(pintype "power_in")
		)
		(pad "A5" smd rect
			(at 1.1375 -4.525 180)
			(size 0.25 1.625)
			(layers "F.Cu" "F.Mask" "F.Paste")
			(net 817 "/USB DP Alt mode/USBC1_CC1")
			(pinfunction "CC_{1}")
			(pintype "bidirectional")
		)
		(pad "A6" smd rect
			(at 1.1375 -4.025 180)
			(size 0.25 1.625)
			(layers "F.Cu" "F.Mask" "F.Paste")
			(net 55 "/SoM_IO2/USB1.D+")
			(pinfunction "D_{A}+")
			(pintype "bidirectional")
		)
		(pad "A7" smd rect
			(at 1.1375 -3.525 180)
			(size 0.25 1.625)
			(layers "F.Cu" "F.Mask" "F.Paste")
			(net 140 "/SoM_IO2/USB1.D-")
			(pinfunction "D_{A}-")
			(pintype "bidirectional")
		)
		(pad "A8" smd rect
			(at 1.1375 -3.025 180)
			(size 0.25 1.625)
			(layers "F.Cu" "F.Mask" "F.Paste")
			(net 821 "/USB DP Alt mode/USBC1_SBU_N")
			(pinfunction "SBU_{1}")
			(pintype "bidirectional")
		)
		(pad "A9" smd rect
			(at 1.1375 -2.525 180)
			(size 0.25 1.625)
			(layers "F.Cu" "F.Mask" "F.Paste")
			(net 376 "/USB DP Alt mode/USBC1_VBUS")
			(pinfunction "VBUS")
			(pintype "passive")
		)
		(pad "A10" smd rect
			(at 1.1375 -2.025 180)
			(size 0.25 1.625)
			(layers "F.Cu" "F.Mask" "F.Paste")
			(net 820 "/USB DP Alt mode/USBC1_RX2_N")
			(pinfunction "RX_{2}-")
			(pintype "bidirectional")
		)
		(pad "A11" smd rect
			(at 1.1375 -1.525 180)
			(size 0.25 1.625)
			(layers "F.Cu" "F.Mask" "F.Paste")
			(net 818 "/USB DP Alt mode/USBC1_RX2_P")
			(pinfunction "RX_{2}+")
			(pintype "bidirectional")
		)
		(pad "A12" smd rect
			(at 1.1375 -1.025 180)
			(size 0.25 1.625)
			(layers "F.Cu" "F.Mask" "F.Paste")
			(net 1 "GND")
			(pinfunction "GND")
			(pintype "passive")
		)
		(pad "B1" smd rect
			(at -1.1375 -1.025 180)
			(size 0.25 1.625)
			(layers "F.Cu" "F.Mask" "F.Paste")
			(net 1 "GND")
			(pinfunction "GND")
			(pintype "passive")
		)
		(pad "B2" smd rect
			(at -1.1375 -1.525 180)
			(size 0.25 1.625)
			(layers "F.Cu" "F.Mask" "F.Paste")
			(net 347 "/USB DP Alt mode/USBC1_CONN_TX2_P")
			(pinfunction "TX_{2}+")
			(pintype "bidirectional")
		)
		(pad "B3" smd rect
			(at -1.1375 -2.025 180)
			(size 0.25 1.625)
			(layers "F.Cu" "F.Mask" "F.Paste")
			(net 374 "/USB DP Alt mode/USBC1_CONN_TX2_N")
			(pinfunction "TX_{2}-")
			(pintype "bidirectional")
		)
		(pad "B4" smd rect
			(at -1.1375 -2.525 180)
			(size 0.25 1.625)
			(layers "F.Cu" "F.Mask" "F.Paste")
			(net 376 "/USB DP Alt mode/USBC1_VBUS")
			(pinfunction "VBUS")
			(pintype "passive")
		)
		(pad "B5" smd rect
			(at -1.1375 -3.025 180)
			(size 0.25 1.625)
			(layers "F.Cu" "F.Mask" "F.Paste")
			(net 816 "/USB DP Alt mode/USBC1_CC2")
			(pinfunction "CC_{2}")
			(pintype "bidirectional")
		)
		(pad "B6" smd rect
			(at -1.1375 -3.525 180)
			(size 0.25 1.625)
			(layers "F.Cu" "F.Mask" "F.Paste")
			(net 55 "/SoM_IO2/USB1.D+")
			(pinfunction "D_{B}+")
			(pintype "bidirectional")
		)
		(pad "B7" smd rect
			(at -1.1375 -4.025 180)
			(size 0.25 1.625)
			(layers "F.Cu" "F.Mask" "F.Paste")
			(net 140 "/SoM_IO2/USB1.D-")
			(pinfunction "D_{B}-")
			(pintype "bidirectional")
		)
		(pad "B8" smd rect
			(at -1.1375 -4.525 180)
			(size 0.25 1.625)
			(layers "F.Cu" "F.Mask" "F.Paste")
			(net 815 "/USB DP Alt mode/USBC1_SBU_P")
			(pinfunction "SBU_{2}")
			(pintype "bidirectional")
		)
		(pad "B9" smd rect
			(at -1.1375 -5.025 180)
			(size 0.25 1.625)
			(layers "F.Cu" "F.Mask" "F.Paste")
			(net 376 "/USB DP Alt mode/USBC1_VBUS")
			(pinfunction "VBUS")
			(pintype "passive")
		)
		(pad "B10" smd rect
			(at -1.1375 -5.525 180)
			(size 0.25 1.625)
			(layers "F.Cu" "F.Mask" "F.Paste")
			(net 819 "/USB DP Alt mode/USBC1_RX1_N")
			(pinfunction "RX_{1}-")
			(pintype "bidirectional")
		)
		(pad "B11" smd rect
			(at -1.1375 -6.025 180)
			(size 0.25 1.625)
			(layers "F.Cu" "F.Mask" "F.Paste")
			(net 822 "/USB DP Alt mode/USBC1_RX1_P")
			(pinfunction "RX_{1}+")
			(pintype "bidirectional")
		)
		(pad "B12" smd rect
			(at -1.1375 -6.525 180)
			(size 0.25 1.625)
			(layers "F.Cu" "F.Mask" "F.Paste")
			(net 1 "GND")
			(pinfunction "GND")
			(pintype "passive")
		)
		(pad "SH" thru_hole oval
			(at -3 -7.849 90)
			(size 1 2.05)
			(drill oval 0.6 1.65)
			(layers "*.Cu" "*.Mask")
			(remove_unused_layers no)
			(net 1 "GND")
			(pinfunction "SH")
			(pintype "passive")
		)
		(pad "SH" thru_hole oval
			(at -3 0.25 90)
			(size 1 2.05)
			(drill oval 0.6 1.65)
			(layers "*.Cu" "*.Mask")
			(remove_unused_layers no)
			(net 1 "GND")
			(pinfunction "SH")
			(pintype "passive")
		)
		(pad "SH" thru_hole oval
			(at 3 -7.849 90)
			(size 1 2.05)
			(drill oval 0.6 1.65)
			(layers "*.Cu" "*.Mask")
			(remove_unused_layers no)
			(net 1 "GND")
			(pinfunction "SH")
			(pintype "passive")
		)
		(pad "SH" thru_hole oval
			(at 3 0.25 90)
			(size 1 2.05)
			(drill oval 0.6 1.65)
			(layers "*.Cu" "*.Mask")
			(remove_unused_layers no)
			(net 1 "GND")
			(pinfunction "SH")
			(pintype "passive")
		)
	)
	(footprint "antmicro-footprints:SOD-523"
		(layer "F.Cu")
		(at 171.7 113.999 90)
		(property "Reference" "D8"
			(at 0.999 -0.8 180)
			(layer "F.SilkS")
			(effects
				(font
					(size 0.7 0.7)
					(thickness 0.15)
				)
				(justify left bottom)
			)
		)
		(property "Value" "PESD5Z5.0F"
			(at 0 1.499 90)
			(layer "F.Fab")
			(effects
				(font
					(size 0.7 0.7)
					(thickness 0.15)
				)
				(justify left bottom)
			)
		)
		(property "Datasheet" "https://assets.nexperia.com/documents/data-sheet/PESD5Z5_0.pdf"
			(at 0 0 90)
			(layer "F.Fab")
			(hide yes)
			(effects
				(font
					(size 1.27 1.27)
					(thickness 0.15)
				)
			)
		)
		(property "Description" "Unidirectional TVS, 30 kV,  SOD-523, 5 V, 89 pF"
			(at 0 0 90)
			(layer "F.Fab")
			(hide yes)
			(effects
				(font
					(size 1.27 1.27)
					(thickness 0.15)
				)
			)
		)
		(property "Manufacturer" "Nexperia"
			(at 0 0 90)
			(unlocked yes)
			(layer "F.Fab")
			(hide yes)
			(effects
				(font
					(size 1 1)
					(thickness 0.15)
				)
			)
		)
		(property "MPN" "PESD5Z5.0F"
			(at 0 0 90)
			(unlocked yes)
			(layer "F.Fab")
			(hide yes)
			(effects
				(font
					(size 1 1)
					(thickness 0.15)
				)
			)
		)
		(property "Author" "Antmicro"
			(at 0 0 90)
			(unlocked yes)
			(layer "F.Fab")
			(hide yes)
			(effects
				(font
					(size 1 1)
					(thickness 0.15)
				)
			)
		)
		(property "License" "Apache-2.0"
			(at 0 0 90)
			(unlocked yes)
			(layer "F.Fab")
			(hide yes)
			(effects
				(font
					(size 1 1)
					(thickness 0.15)
				)
			)
		)
		(sheetname "/DCDC/")
		(sheetfile "dcdc.kicad_sch")
		(attr smd)
		(fp_line
			(start -0.35 -0.5)
			(end -0.35 0.5)
			(stroke
				(width 0.15)
				(type solid)
			)
			(layer "F.SilkS")
		)
		(fp_rect
			(start -1 -0.6)
			(end 1 0.6)
			(stroke
				(width 0.05)
				(type solid)
			)
			(fill no)
			(layer "F.CrtYd")
		)
		(fp_line
			(start 0.65 -0.425)
			(end 0.65 0.423)
			(stroke
				(width 0.15)
				(type solid)
			)
			(layer "F.Fab")
		)
		(fp_line
			(start -0.652 -0.425)
			(end 0.65 -0.425)
			(stroke
				(width 0.15)
				(type solid)
			)
			(layer "F.Fab")
		)
		(fp_line
			(start -0.35 -0.4)
			(end -0.35 0.4)
			(stroke
				(width 0.15)
				(type solid)
			)
			(layer "F.Fab")
		)
		(fp_line
			(start -0.652 0.423)
			(end -0.652 -0.425)
			(stroke
				(width 0.15)
				(type solid)
			)
			(layer "F.Fab")
		)
		(fp_line
			(start -0.652 0.423)
			(end 0.65 0.423)
			(stroke
				(width 0.15)
				(type solid)
			)
			(layer "F.Fab")
		)
		(fp_text user "${REFERENCE}"
			(at -1.276 3.499 90)
			(layer "F.Fab")
			(effects
				(font
					(size 0.7 0.7)
					(thickness 0.15)
				)
				(justify left bottom)
			)
		)
		(fp_text user "License: Apache-2.0"
			(at -1.276 5.9 90)
			(layer "F.Fab")
			(effects
				(font
					(size 0.7 0.7)
					(thickness 0.15)
				)
				(justify left bottom)
			)
		)
		(fp_text user "Author: Antmicro"
			(at -1.276 4.7 90)
			(layer "F.Fab")
			(effects
				(font
					(size 0.7 0.7)
					(thickness 0.15)
				)
				(justify left bottom)
			)
		)
		(pad "1" smd roundrect
			(at -0.701 0 90)
			(size 0.5 0.6)
			(layers "F.Cu" "F.Mask" "F.Paste")
			(roundrect_rratio 0.25)
			(net 5 "+5V")
			(pinfunction "C")
			(pintype "passive")
		)
		(pad "2" smd roundrect
			(at 0.699 0 90)
			(size 0.5 0.6)
			(layers "F.Cu" "F.Mask" "F.Paste")
			(roundrect_rratio 0.25)
			(net 1 "GND")
			(pinfunction "A")
			(pintype "passive")
		)
	)
	(footprint "antmicro-footprints:TSOT23-6"
		(layer "F.Cu")
		(at 62.41 89.04 90)
		(property "Reference" "U45"
			(at -0.12 2.59 90)
			(layer "F.SilkS")
			(effects
				(font
					(size 0.7 0.7)
					(thickness 0.15)
				)
				(justify left bottom)
			)
		)
		(property "Value" "AP22615A_TSOT26"
			(at 0 2.6 90)
			(layer "F.Fab")
			(effects
				(font
					(size 0.7 0.7)
					(thickness 0.15)
				)
				(justify left bottom)
			)
		)
		(property "Datasheet" "https://www.mouser.com/datasheet/2/115/DIOD_S_A0008958405_1-2543193.pdf"
			(at 0 0 90)
			(layer "F.Fab")
			(hide yes)
			(effects
				(font
					(size 1.27 1.27)
					(thickness 0.15)
				)
			)
		)
		(property "Description" "Power Load Distribution Switch, High Side, Active High, 1 Output, 5.5 V, 3.6 A, 0.04 ohm, TSOT-26-6"
			(at 0 0 90)
			(layer "F.Fab")
			(hide yes)
			(effects
				(font
					(size 1.27 1.27)
					(thickness 0.15)
				)
			)
		)
		(property "MPN" "AP22615AWU-7"
			(at 0 0 90)
			(unlocked yes)
			(layer "F.Fab")
			(hide yes)
			(effects
				(font
					(size 1 1)
					(thickness 0.15)
				)
			)
		)
		(property "Manufacturer" "Diodes Incorporated"
			(at 0 0 90)
			(unlocked yes)
			(layer "F.Fab")
			(hide yes)
			(effects
				(font
					(size 1 1)
					(thickness 0.15)
				)
			)
		)
		(property "Author" "Antmicro"
			(at 0 0 90)
			(unlocked yes)
			(layer "F.Fab")
			(hide yes)
			(effects
				(font
					(size 1 1)
					(thickness 0.15)
				)
			)
		)
		(property "License" "Apache-2.0"
			(at 0 0 90)
			(unlocked yes)
			(layer "F.Fab")
			(hide yes)
			(effects
				(font
					(size 1 1)
					(thickness 0.15)
				)
			)
		)
		(sheetname "/CSI/")
		(sheetfile "csi.kicad_sch")
		(attr smd)
		(fp_line
			(start -1 -1.5)
			(end -1 -1.375)
			(stroke
				(width 0.15)
				(type solid)
			)
			(layer "F.SilkS")
		)
		(fp_line
			(start 1 -1.497)
			(end -1 -1.5)
			(stroke
				(width 0.15)
				(type solid)
			)
			(layer "F.SilkS")
		)
		(fp_line
			(start 1 -1.497)
			(end 1 -1.375)
			(stroke
				(width 0.15)
				(type solid)
			)
			(layer "F.SilkS")
		)
		(fp_line
			(start 1 1.55)
			(end 1 1.4)
			(stroke
				(width 0.15)
				(type solid)
			)
			(layer "F.SilkS")
		)
		(fp_line
			(start 1 1.55)
			(end -1 1.55)
			(stroke
				(width 0.15)
				(type solid)
			)
			(layer "F.SilkS")
		)
		(fp_line
			(start -1 1.55)
			(end -1 1.4)
			(stroke
				(width 0.15)
				(type solid)
			)
			(layer "F.SilkS")
		)
		(fp_circle
			(center -1.44 -1.5)
			(end -1.39 -1.5)
			(stroke
				(width 0.15)
				(type solid)
			)
			(fill yes)
			(layer "F.SilkS")
		)
		(fp_rect
			(start 1.93 -1.7)
			(end -1.93 1.7)
			(stroke
				(width 0.05)
				(type solid)
			)
			(fill no)
			(layer "F.CrtYd")
		)
		(fp_line
			(start -0.45 -1.521)
			(end -0.876 -1.096)
			(stroke
				(width 0.15)
				(type solid)
			)
			(layer "F.Fab")
		)
		(fp_rect
			(start 0.875 1.528)
			(end -0.875 -1.525)
			(stroke
				(width 0.15)
				(type solid)
			)
			(fill no)
			(layer "F.Fab")
		)
		(fp_text user "Author: Antmicro"
			(at -1.93 5 90)
			(layer "F.Fab")
			(effects
				(font
					(size 0.7 0.7)
					(thickness 0.15)
				)
				(justify left bottom)
			)
		)
		(fp_text user "${REFERENCE}"
			(at -1.93 3.8 90)
			(layer "F.Fab")
			(effects
				(font
					(size 0.7 0.7)
					(thickness 0.15)
				)
				(justify left bottom)
			)
		)
		(fp_text user "License: Apache-2.0"
			(at -1.93 6.199 90)
			(layer "F.Fab")
			(effects
				(font
					(size 0.7 0.7)
					(thickness 0.15)
				)
				(justify left bottom)
			)
		)
		(pad "1" smd rect
			(at -1.301 -0.947)
			(size 0.7 1.2)
			(layers "F.Cu" "F.Mask" "F.Paste")
			(net 6 "/CSI/CSIA_3V3")
			(pinfunction "OUT")
			(pintype "power_out")
		)
		(pad "2" smd rect
			(at -1.301 0.004)
			(size 0.7 1.2)
			(layers "F.Cu" "F.Mask" "F.Paste")
			(net 1 "GND")
			(pinfunction "GND")
			(pintype "power_in")
		)
		(pad "3" smd rect
			(at -1.301 0.954)
			(size 0.7 1.2)
			(layers "F.Cu" "F.Mask" "F.Paste")
			(net 98 "/CSI/CAM_CTRL.CSIA_FLG")
			(pinfunction "FLG")
			(pintype "output")
		)
		(pad "4" smd rect
			(at 1.299 0.954)
			(size 0.7 1.2)
			(layers "F.Cu" "F.Mask" "F.Paste")
			(net 74 "/CSI/CAM_CTRL.CSIA_PEN")
			(pinfunction "EN")
			(pintype "input")
		)
		(pad "5" smd rect
			(at 1.299 0.004)
			(size 0.7 1.2)
			(layers "F.Cu" "F.Mask" "F.Paste")
			(net 996 "/CSI/CSIA_3V3_ISET")
			(pinfunction "ISET")
			(pintype "passive")
		)
		(pad "6" smd rect
			(at 1.299 -0.947)
			(size 0.7 1.2)
			(layers "F.Cu" "F.Mask" "F.Paste")
			(net 2 "+3V3")
			(pinfunction "IN")
			(pintype "power_in")
		)
	)
)
